(kicad_pcb
	(version 20260206)
	(generator "pcbnew")
	(generator_version "10.0")
	(general
		(thickness 1.6)
		(legacy_teardrops no)
	)
	(paper "A4")
	(title_block
		(title "01162023_DA0F0TEBIF0_F0T_Expander_BD_F_brd_V02_OCP.brd")
		(comment 1 "Grand Teton / footprints 5859-5864 of 9728")
	)
	(layers
		(0 "F.Cu" signal "TOP")
		(4 "In1.Cu" signal "GND")
		(6 "In2.Cu" signal "VCC")
		(8 "In3.Cu" signal "VCC1")
		(10 "In4.Cu" signal "GND1")
		(12 "In5.Cu" signal "IN1")
		(14 "In6.Cu" signal "GND2")
		(16 "In7.Cu" signal "IN2")
		(18 "In8.Cu" signal "GND3")
		(20 "In9.Cu" signal "IN3")
		(22 "In10.Cu" signal "GND4")
		(24 "In11.Cu" signal "IN4")
		(26 "In12.Cu" signal "GND5")
		(28 "In13.Cu" signal "IN5")
		(30 "In14.Cu" signal "GND6")
		(32 "In15.Cu" signal "IN6")
		(34 "In16.Cu" signal "GND7")
		(2 "B.Cu" signal "BOTTOM")
		(9 "F.Adhes" user "F.Adhesive")
		(11 "B.Adhes" user "B.Adhesive")
		(13 "F.Paste" user "Package Geometry/Pastemask Top")
		(15 "B.Paste" user "Package Geometry/Pastemask Bottom")
		(5 "F.SilkS" user "Ref Des/Silkscreen Top")
		(7 "B.SilkS" user "Ref Des/Silkscreen Bottom")
		(1 "F.Mask" user "Board Geometry/Soldermask Top")
		(3 "B.Mask" user "Board Geometry/Soldermask Bottom")
		(17 "Dwgs.User" user "User.Drawings")
		(19 "Cmts.User" user "User.Comments")
		(21 "Eco1.User" user "User.Eco1")
		(23 "Eco2.User" user "User.Eco2")
		(25 "Edge.Cuts" user "Board Geometry/Outline")
		(27 "Margin" user)
		(31 "F.CrtYd" user "Package Geometry/Place Bound Top")
		(29 "B.CrtYd" user "Package Geometry/Place Bound Bottom")
		(35 "F.Fab" user "Ref Des/Assembly Top")
		(33 "B.Fab" user "Ref Des/Assembly Bottom")
	)
	(footprint ""
		(layer "F.Cu")
		(at 151.50719 -380.379732 180)
		(property "Reference" "C4098"
			(at 0 0 180)
			(layer "F.SilkS")
			(hide yes)
			(effects
				(font
					(size 1.27 1.27)
				)
			)
		)
		(property "Value" ""
			(at 0 0 180)
			(layer "F.Fab")
			(effects
				(font
					(size 1.27 1.27)
				)
			)
		)
		(duplicate_pad_numbers_are_jumpers no)
		(fp_line
			(start 0.7874 0.4064)
			(end -0.7874 0.4064)
			(stroke
				(width 0.1524)
				(type default)
			)
			(layer "F.SilkS")
		)
		(fp_line
			(start 0.7874 -0.4064)
			(end 0.7874 0.4064)
			(stroke
				(width 0.1524)
				(type default)
			)
			(layer "F.SilkS")
		)
		(fp_line
			(start -0.7874 0.4064)
			(end -0.7874 -0.4064)
			(stroke
				(width 0.1524)
				(type default)
			)
			(layer "F.SilkS")
		)
		(fp_line
			(start -0.7874 -0.4064)
			(end 0.7874 -0.4064)
			(stroke
				(width 0.1524)
				(type default)
			)
			(layer "F.SilkS")
		)
		(fp_line
			(start 0.67945 0.3048)
			(end 0.120396 0.3048)
			(stroke
				(width 0.1)
				(type default)
			)
			(layer "F.Fab")
		)
		(fp_line
			(start 0.67945 -0.3048)
			(end 0.67945 0.3048)
			(stroke
				(width 0.1)
				(type default)
			)
			(layer "F.Fab")
		)
		(fp_line
			(start 0.12065 -0.2794)
			(end 0.12065 -0.3048)
			(stroke
				(width 0.1)
				(type default)
			)
			(layer "F.Fab")
		)
		(fp_line
			(start 0.12065 -0.3048)
			(end 0.67945 -0.3048)
			(stroke
				(width 0.1)
				(type default)
			)
			(layer "F.Fab")
		)
		(fp_line
			(start 0.120396 0.3048)
			(end 0.120396 0.2794)
			(stroke
				(width 0.1)
				(type default)
			)
			(layer "F.Fab")
		)
		(fp_line
			(start 0.120396 0.2794)
			(end -0.12065 0.2794)
			(stroke
				(width 0.1)
				(type default)
			)
			(layer "F.Fab")
		)
		(fp_line
			(start -0.12065 0.3048)
			(end -0.67945 0.3048)
			(stroke
				(width 0.1)
				(type default)
			)
			(layer "F.Fab")
		)
		(fp_line
			(start -0.12065 0.2794)
			(end -0.12065 0.3048)
			(stroke
				(width 0.1)
				(type default)
			)
			(layer "F.Fab")
		)
		(fp_line
			(start -0.12065 -0.2794)
			(end 0.12065 -0.2794)
			(stroke
				(width 0.1)
				(type default)
			)
			(layer "F.Fab")
		)
		(fp_line
			(start -0.12065 -0.305054)
			(end -0.12065 -0.2794)
			(stroke
				(width 0.1)
				(type default)
			)
			(layer "F.Fab")
		)
		(fp_line
			(start -0.67945 0.3048)
			(end -0.67945 -0.305054)
			(stroke
				(width 0.1)
				(type default)
			)
			(layer "F.Fab")
		)
		(fp_line
			(start -0.67945 -0.305054)
			(end -0.12065 -0.305054)
			(stroke
				(width 0.1)
				(type default)
			)
			(layer "F.Fab")
		)
		(pad "1" smd circle
			(at -0.40005 0 180)
			(size 0 0)
			(layers "F.Cu" "F.Mask" "F.Paste")
			(net "GND")
		)
		(pad "2" smd circle
			(at 0.40005 0 180)
			(size 0 0)
			(layers "F.Cu" "F.Mask" "F.Paste")
			(net "GPU_3V3IO_RSVD0_FFU")
		)
	)
	(footprint ""
		(layer "F.Cu")
		(at 114.802158 -162.122866 180)
		(property "Reference" "PR61"
			(at 0 0 180)
			(layer "F.SilkS")
			(hide yes)
			(effects
				(font
					(size 1.27 1.27)
				)
			)
		)
		(property "Value" ""
			(at 0 0 180)
			(layer "F.Fab")
			(effects
				(font
					(size 1.27 1.27)
				)
			)
		)
		(duplicate_pad_numbers_are_jumpers no)
		(fp_line
			(start 0.7874 0.4064)
			(end -0.7874 0.4064)
			(stroke
				(width 0.1524)
				(type default)
			)
			(layer "F.SilkS")
		)
		(fp_line
			(start 0.7874 -0.4064)
			(end 0.7874 0.4064)
			(stroke
				(width 0.1524)
				(type default)
			)
			(layer "F.SilkS")
		)
		(fp_line
			(start -0.7874 0.4064)
			(end -0.7874 -0.4064)
			(stroke
				(width 0.1524)
				(type default)
			)
			(layer "F.SilkS")
		)
		(fp_line
			(start -0.7874 -0.4064)
			(end 0.7874 -0.4064)
			(stroke
				(width 0.1524)
				(type default)
			)
			(layer "F.SilkS")
		)
		(fp_line
			(start 0.67945 0.3048)
			(end 0.120396 0.3048)
			(stroke
				(width 0.1)
				(type default)
			)
			(layer "F.Fab")
		)
		(fp_line
			(start 0.67945 -0.3048)
			(end 0.67945 0.3048)
			(stroke
				(width 0.1)
				(type default)
			)
			(layer "F.Fab")
		)
		(fp_line
			(start 0.12065 -0.2794)
			(end 0.12065 -0.3048)
			(stroke
				(width 0.1)
				(type default)
			)
			(layer "F.Fab")
		)
		(fp_line
			(start 0.12065 -0.3048)
			(end 0.67945 -0.3048)
			(stroke
				(width 0.1)
				(type default)
			)
			(layer "F.Fab")
		)
		(fp_line
			(start 0.120396 0.3048)
			(end 0.120396 0.2794)
			(stroke
				(width 0.1)
				(type default)
			)
			(layer "F.Fab")
		)
		(fp_line
			(start 0.120396 0.2794)
			(end -0.12065 0.2794)
			(stroke
				(width 0.1)
				(type default)
			)
			(layer "F.Fab")
		)
		(fp_line
			(start -0.12065 0.3048)
			(end -0.67945 0.3048)
			(stroke
				(width 0.1)
				(type default)
			)
			(layer "F.Fab")
		)
		(fp_line
			(start -0.12065 0.2794)
			(end -0.12065 0.3048)
			(stroke
				(width 0.1)
				(type default)
			)
			(layer "F.Fab")
		)
		(fp_line
			(start -0.12065 -0.2794)
			(end 0.12065 -0.2794)
			(stroke
				(width 0.1)
				(type default)
			)
			(layer "F.Fab")
		)
		(fp_line
			(start -0.12065 -0.305054)
			(end -0.12065 -0.2794)
			(stroke
				(width 0.1)
				(type default)
			)
			(layer "F.Fab")
		)
		(fp_line
			(start -0.67945 0.3048)
			(end -0.67945 -0.305054)
			(stroke
				(width 0.1)
				(type default)
			)
			(layer "F.Fab")
		)
		(fp_line
			(start -0.67945 -0.305054)
			(end -0.12065 -0.305054)
			(stroke
				(width 0.1)
				(type default)
			)
			(layer "F.Fab")
		)
		(pad "1" smd circle
			(at -0.40005 0 180)
			(size 0 0)
			(layers "F.Cu" "F.Mask" "F.Paste")
			(net "SH_P3V3_AUX_FB")
		)
		(pad "2" smd circle
			(at 0.40005 0 180)
			(size 0 0)
			(layers "F.Cu" "F.Mask" "F.Paste")
			(net "P3V3_AUX_FB")
		)
	)
	(footprint ""
		(layer "F.Cu")
		(at 109.347 -38.49116 180)
		(property "Reference" "R6064"
			(at 0 0 180)
			(layer "F.SilkS")
			(hide yes)
			(effects
				(font
					(size 1.27 1.27)
				)
			)
		)
		(property "Value" ""
			(at 0 0 180)
			(layer "F.Fab")
			(effects
				(font
					(size 1.27 1.27)
				)
			)
		)
		(duplicate_pad_numbers_are_jumpers no)
		(fp_line
			(start 0.7874 0.4064)
			(end -0.7874 0.4064)
			(stroke
				(width 0.1524)
				(type default)
			)
			(layer "F.SilkS")
		)
		(fp_line
			(start 0.7874 -0.4064)
			(end 0.7874 0.4064)
			(stroke
				(width 0.1524)
				(type default)
			)
			(layer "F.SilkS")
		)
		(fp_line
			(start -0.7874 0.4064)
			(end -0.7874 -0.4064)
			(stroke
				(width 0.1524)
				(type default)
			)
			(layer "F.SilkS")
		)
		(fp_line
			(start -0.7874 -0.4064)
			(end 0.7874 -0.4064)
			(stroke
				(width 0.1524)
				(type default)
			)
			(layer "F.SilkS")
		)
		(fp_line
			(start 0.67945 0.3048)
			(end 0.120396 0.3048)
			(stroke
				(width 0.1)
				(type default)
			)
			(layer "F.Fab")
		)
		(fp_line
			(start 0.67945 -0.3048)
			(end 0.67945 0.3048)
			(stroke
				(width 0.1)
				(type default)
			)
			(layer "F.Fab")
		)
		(fp_line
			(start 0.12065 -0.2794)
			(end 0.12065 -0.3048)
			(stroke
				(width 0.1)
				(type default)
			)
			(layer "F.Fab")
		)
		(fp_line
			(start 0.12065 -0.3048)
			(end 0.67945 -0.3048)
			(stroke
				(width 0.1)
				(type default)
			)
			(layer "F.Fab")
		)
		(fp_line
			(start 0.120396 0.3048)
			(end 0.120396 0.2794)
			(stroke
				(width 0.1)
				(type default)
			)
			(layer "F.Fab")
		)
		(fp_line
			(start 0.120396 0.2794)
			(end -0.12065 0.2794)
			(stroke
				(width 0.1)
				(type default)
			)
			(layer "F.Fab")
		)
		(fp_line
			(start -0.12065 0.3048)
			(end -0.67945 0.3048)
			(stroke
				(width 0.1)
				(type default)
			)
			(layer "F.Fab")
		)
		(fp_line
			(start -0.12065 0.2794)
			(end -0.12065 0.3048)
			(stroke
				(width 0.1)
				(type default)
			)
			(layer "F.Fab")
		)
		(fp_line
			(start -0.12065 -0.2794)
			(end 0.12065 -0.2794)
			(stroke
				(width 0.1)
				(type default)
			)
			(layer "F.Fab")
		)
		(fp_line
			(start -0.12065 -0.305054)
			(end -0.12065 -0.2794)
			(stroke
				(width 0.1)
				(type default)
			)
			(layer "F.Fab")
		)
		(fp_line
			(start -0.67945 0.3048)
			(end -0.67945 -0.305054)
			(stroke
				(width 0.1)
				(type default)
			)
			(layer "F.Fab")
		)
		(fp_line
			(start -0.67945 -0.305054)
			(end -0.12065 -0.305054)
			(stroke
				(width 0.1)
				(type default)
			)
			(layer "F.Fab")
		)
		(pad "1" smd circle
			(at -0.40005 0 180)
			(size 0 0)
			(layers "F.Cu" "F.Mask" "F.Paste")
			(net "P3V3_SSD4_PG_G1")
		)
		(pad "2" smd circle
			(at 0.40005 0 180)
			(size 0 0)
			(layers "F.Cu" "F.Mask" "F.Paste")
			(net "GND")
		)
	)
	(footprint ""
		(layer "F.Cu")
		(at 134.822692 -44.341542 90)
		(property "Reference" "R558"
			(at 0 0 90)
			(layer "F.SilkS")
			(hide yes)
			(effects
				(font
					(size 1.27 1.27)
				)
			)
		)
		(property "Value" ""
			(at 0 0 90)
			(layer "F.Fab")
			(effects
				(font
					(size 1.27 1.27)
				)
			)
		)
		(duplicate_pad_numbers_are_jumpers no)
		(fp_line
			(start 0.7874 -0.4064)
			(end 0.7874 0.4064)
			(stroke
				(width 0.1524)
				(type default)
			)
			(layer "F.SilkS")
		)
		(fp_line
			(start -0.7874 -0.4064)
			(end 0.7874 -0.4064)
			(stroke
				(width 0.1524)
				(type default)
			)
			(layer "F.SilkS")
		)
		(fp_line
			(start 0.7874 0.4064)
			(end -0.7874 0.4064)
			(stroke
				(width 0.1524)
				(type default)
			)
			(layer "F.SilkS")
		)
		(fp_line
			(start -0.7874 0.4064)
			(end -0.7874 -0.4064)
			(stroke
				(width 0.1524)
				(type default)
			)
			(layer "F.SilkS")
		)
		(fp_line
			(start -0.12065 -0.305054)
			(end -0.12065 -0.2794)
			(stroke
				(width 0.1)
				(type default)
			)
			(layer "F.Fab")
		)
		(fp_line
			(start -0.67945 -0.305054)
			(end -0.12065 -0.305054)
			(stroke
				(width 0.1)
				(type default)
			)
			(layer "F.Fab")
		)
		(fp_line
			(start 0.67945 -0.3048)
			(end 0.67945 0.3048)
			(stroke
				(width 0.1)
				(type default)
			)
			(layer "F.Fab")
		)
		(fp_line
			(start 0.12065 -0.3048)
			(end 0.67945 -0.3048)
			(stroke
				(width 0.1)
				(type default)
			)
			(layer "F.Fab")
		)
		(fp_line
			(start 0.12065 -0.2794)
			(end 0.12065 -0.3048)
			(stroke
				(width 0.1)
				(type default)
			)
			(layer "F.Fab")
		)
		(fp_line
			(start -0.12065 -0.2794)
			(end 0.12065 -0.2794)
			(stroke
				(width 0.1)
				(type default)
			)
			(layer "F.Fab")
		)
		(fp_line
			(start 0.120396 0.2794)
			(end -0.12065 0.2794)
			(stroke
				(width 0.1)
				(type default)
			)
			(layer "F.Fab")
		)
		(fp_line
			(start -0.12065 0.2794)
			(end -0.12065 0.3048)
			(stroke
				(width 0.1)
				(type default)
			)
			(layer "F.Fab")
		)
		(fp_line
			(start 0.67945 0.3048)
			(end 0.120396 0.3048)
			(stroke
				(width 0.1)
				(type default)
			)
			(layer "F.Fab")
		)
		(fp_line
			(start 0.120396 0.3048)
			(end 0.120396 0.2794)
			(stroke
				(width 0.1)
				(type default)
			)
			(layer "F.Fab")
		)
		(fp_line
			(start -0.12065 0.3048)
			(end -0.67945 0.3048)
			(stroke
				(width 0.1)
				(type default)
			)
			(layer "F.Fab")
		)
		(fp_line
			(start -0.67945 0.3048)
			(end -0.67945 -0.305054)
			(stroke
				(width 0.1)
				(type default)
			)
			(layer "F.Fab")
		)
		(pad "1" smd circle
			(at -0.40005 0 90)
			(size 0 0)
			(layers "F.Cu" "F.Mask" "F.Paste")
			(net "P12V_SSD4")
		)
		(pad "2" smd circle
			(at 0.40005 0 90)
			(size 0 0)
			(layers "F.Cu" "F.Mask" "F.Paste")
			(net "P12V_SSD4_VIN_N")
		)
	)
	(footprint ""
		(layer "F.Cu")
		(at 420.787576 -25.342342 -90)
		(property "Reference" "R452"
			(at 0 0 270)
			(layer "F.SilkS")
			(hide yes)
			(effects
				(font
					(size 1.27 1.27)
				)
			)
		)
		(property "Value" ""
			(at 0 0 270)
			(layer "F.Fab")
			(effects
				(font
					(size 1.27 1.27)
				)
			)
		)
		(duplicate_pad_numbers_are_jumpers no)
		(fp_line
			(start -0.7874 0.4064)
			(end -0.7874 -0.4064)
			(stroke
				(width 0.1524)
				(type default)
			)
			(layer "F.SilkS")
		)
		(fp_line
			(start 0.7874 0.4064)
			(end -0.7874 0.4064)
			(stroke
				(width 0.1524)
				(type default)
			)
			(layer "F.SilkS")
		)
		(fp_line
			(start -0.7874 -0.4064)
			(end 0.7874 -0.4064)
			(stroke
				(width 0.1524)
				(type default)
			)
			(layer "F.SilkS")
		)
		(fp_line
			(start 0.7874 -0.4064)
			(end 0.7874 0.4064)
			(stroke
				(width 0.1524)
				(type default)
			)
			(layer "F.SilkS")
		)
		(fp_line
			(start -0.67945 0.3048)
			(end -0.67945 -0.305054)
			(stroke
				(width 0.1)
				(type default)
			)
			(layer "F.Fab")
		)
		(fp_line
			(start -0.12065 0.3048)
			(end -0.67945 0.3048)
			(stroke
				(width 0.1)
				(type default)
			)
			(layer "F.Fab")
		)
		(fp_line
			(start 0.120396 0.3048)
			(end 0.120396 0.2794)
			(stroke
				(width 0.1)
				(type default)
			)
			(layer "F.Fab")
		)
		(fp_line
			(start 0.67945 0.3048)
			(end 0.120396 0.3048)
			(stroke
				(width 0.1)
				(type default)
			)
			(layer "F.Fab")
		)
		(fp_line
			(start -0.12065 0.2794)
			(end -0.12065 0.3048)
			(stroke
				(width 0.1)
				(type default)
			)
			(layer "F.Fab")
		)
		(fp_line
			(start 0.120396 0.2794)
			(end -0.12065 0.2794)
			(stroke
				(width 0.1)
				(type default)
			)
			(layer "F.Fab")
		)
		(fp_line
			(start -0.12065 -0.2794)
			(end 0.12065 -0.2794)
			(stroke
				(width 0.1)
				(type default)
			)
			(layer "F.Fab")
		)
		(fp_line
			(start 0.12065 -0.2794)
			(end 0.12065 -0.3048)
			(stroke
				(width 0.1)
				(type default)
			)
			(layer "F.Fab")
		)
		(fp_line
			(start 0.12065 -0.3048)
			(end 0.67945 -0.3048)
			(stroke
				(width 0.1)
				(type default)
			)
			(layer "F.Fab")
		)
		(fp_line
			(start 0.67945 -0.3048)
			(end 0.67945 0.3048)
			(stroke
				(width 0.1)
				(type default)
			)
			(layer "F.Fab")
		)
		(fp_line
			(start -0.67945 -0.305054)
			(end -0.12065 -0.305054)
			(stroke
				(width 0.1)
				(type default)
			)
			(layer "F.Fab")
		)
		(fp_line
			(start -0.12065 -0.305054)
			(end -0.12065 -0.2794)
			(stroke
				(width 0.1)
				(type default)
			)
			(layer "F.Fab")
		)
		(pad "1" smd circle
			(at -0.40005 0 270)
			(size 0 0)
			(layers "F.Cu" "F.Mask" "F.Paste")
			(net "GND")
		)
		(pad "2" smd circle
			(at 0.40005 0 270)
			(size 0 0)
			(layers "F.Cu" "F.Mask" "F.Paste")
			(net "DUALPORT_N_SSD14")
		)
	)
	(footprint ""
		(layer "F.Cu")
		(at 11.113516 -42.419016)
		(property "Reference" "U363"
			(at 0.113284 2.339086 0)
			(unlocked yes)
			(layer "F.SilkS")
			(effects
				(font
					(size 0.7874 0.5842)
					(thickness 0.1524)
				)
			)
		)
		(property "Value" ""
			(at 0 0 0)
			(layer "F.Fab")
			(effects
				(font
					(size 1.27 1.27)
				)
			)
		)
		(duplicate_pad_numbers_are_jumpers no)
		(fp_line
			(start -1.949958 -1.610106)
			(end 1.949958 -1.610106)
			(stroke
				(width 0.1524)
				(type default)
			)
			(layer "F.SilkS")
		)
		(fp_line
			(start -1.949958 1.610106)
			(end -1.949958 -1.610106)
			(stroke
				(width 0.1524)
				(type default)
			)
			(layer "F.SilkS")
		)
		(fp_line
			(start 1.949958 -1.560068)
			(end 1.949958 1.610106)
			(stroke
				(width 0.1524)
				(type default)
			)
			(layer "F.SilkS")
		)
		(fp_line
			(start 1.949958 1.610106)
			(end -1.949958 1.610106)
			(stroke
				(width 0.1524)
				(type default)
			)
			(layer "F.SilkS")
		)
		(fp_line
			(start -0.750062 -1.560068)
			(end 0.750062 -1.560068)
			(stroke
				(width 0.1)
				(type default)
			)
			(layer "F.Fab")
		)
		(fp_line
			(start -0.750062 1.560068)
			(end -0.750062 -1.560068)
			(stroke
				(width 0.1)
				(type default)
			)
			(layer "F.Fab")
		)
		(fp_line
			(start 0.750062 -1.560068)
			(end 0.750062 1.560068)
			(stroke
				(width 0.1)
				(type default)
			)
			(layer "F.Fab")
		)
		(fp_line
			(start 0.750062 1.560068)
			(end -0.750062 1.560068)
			(stroke
				(width 0.1)
				(type default)
			)
			(layer "F.Fab")
		)
		(pad "D" smd rect
			(at 1.100074 0 270)
			(size 1.016 1.4224)
			(layers "F.Cu" "F.Mask" "F.Paste")
			(net "SSD0_AUX_P3V3_EN")
		)
		(pad "G" smd rect
			(at -1.100074 -0.94996 270)
			(size 1.016 1.4224)
			(layers "F.Cu" "F.Mask" "F.Paste")
			(net "PRSNT_SSD0_R1_N")
		)
		(pad "S" smd rect
			(at -1.100074 0.94996 270)
			(size 1.016 1.4224)
			(layers "F.Cu" "F.Mask" "F.Paste")
			(net "GND")
		)
	)
)
